(kicad_pcb
	(version 20240108)
	(generator "pcbnew")
	(generator_version "8.0")
	(general
		(thickness 1.62)
		(legacy_teardrops no)
	)
	(paper "A4")
	(title_block
		(title "Jetson Orin Baseboard")
		(date "2025-03-12")
		(rev "1.3.4")
		(company "Antmicro Ltd")
		(comment 1 "www.antmicro.com")
		(comment 9 "footprints 664-666 of 677")
	)
	(layers
		(0 "F.Cu" signal)
		(1 "In1.Cu" signal)
		(2 "In2.Cu" signal)
		(3 "In3.Cu" signal)
		(4 "In4.Cu" jumper)
		(5 "In5.Cu" signal)
		(6 "In6.Cu" signal)
		(31 "B.Cu" signal)
		(32 "B.Adhes" user "B.Adhesive")
		(33 "F.Adhes" user "F.Adhesive")
		(34 "B.Paste" user)
		(35 "F.Paste" user)
		(36 "B.SilkS" user "B.Silkscreen")
		(37 "F.SilkS" user "F.Silkscreen")
		(38 "B.Mask" user)
		(39 "F.Mask" user)
		(40 "Dwgs.User" user "User.Drawings")
		(41 "Cmts.User" user "User.Comments")
		(42 "Eco1.User" user "User.Eco1")
		(43 "Eco2.User" user "User.Eco2")
		(44 "Edge.Cuts" user)
		(45 "Margin" user)
		(46 "B.CrtYd" user "B.Courtyard")
		(47 "F.CrtYd" user "F.Courtyard")
		(48 "B.Fab" user)
		(49 "F.Fab" user)
	)
	(footprint "antmicro-footprints:C_0402_1005Metric"
		(layer "B.Cu")
		(at 87 110.3 90)
		(descr "Capacitor SMD 0402")
		(tags "capacitor SMD 0402")
		(property "Reference" "C104"
			(at 1.45 -0.45 -90)
			(layer "B.SilkS")
			(effects
				(font
					(size 0.7 0.7)
					(thickness 0.15)
				)
				(justify left bottom mirror)
			)
		)
		(property "Value" "C_100n_0402"
			(at 0 -1.4 -90)
			(layer "B.Fab")
			(effects
				(font
					(size 0.7 0.7)
					(thickness 0.15)
				)
				(justify left bottom mirror)
			)
		)
		(property "Footprint" "antmicro-footprints:C_0402_1005Metric"
			(at 0 0 90)
			(layer "F.Fab")
			(hide yes)
			(effects
				(font
					(size 1.27 1.27)
					(thickness 0.15)
				)
			)
		)
		(property "Datasheet" "https://www.murata.com/products/productdetail?partno=GRM155R61H104KE14%23"
			(at 0 0 90)
			(layer "F.Fab")
			(hide yes)
			(effects
				(font
					(size 1.27 1.27)
					(thickness 0.15)
				)
			)
		)
		(property "Author" "Antmicro"
			(at 197.3 23.3 0)
			(layer "B.Fab")
			(hide yes)
			(effects
				(font
					(size 1 1)
					(thickness 0.15)
				)
				(justify mirror)
			)
		)
		(property "Dielectric" "X5R"
			(at 197.3 23.3 0)
			(layer "B.Fab")
			(hide yes)
			(effects
				(font
					(size 1 1)
					(thickness 0.15)
				)
				(justify mirror)
			)
		)
		(property "License" "Apache-2.0"
			(at 197.3 23.3 0)
			(layer "B.Fab")
			(hide yes)
			(effects
				(font
					(size 1 1)
					(thickness 0.15)
				)
				(justify mirror)
			)
		)
		(property "MPN" "GRM155R61H104KE14D"
			(at 197.3 23.3 0)
			(layer "B.Fab")
			(hide yes)
			(effects
				(font
					(size 1 1)
					(thickness 0.15)
				)
				(justify mirror)
			)
		)
		(property "Manufacturer" "Murata"
			(at 197.3 23.3 0)
			(layer "B.Fab")
			(hide yes)
			(effects
				(font
					(size 1 1)
					(thickness 0.15)
				)
				(justify mirror)
			)
		)
		(property "Val" "100n"
			(at 197.3 23.3 0)
			(layer "B.Fab")
			(hide yes)
			(effects
				(font
					(size 1 1)
					(thickness 0.15)
				)
				(justify mirror)
			)
		)
		(property "Voltage" "50V"
			(at 197.3 23.3 0)
			(layer "B.Fab")
			(hide yes)
			(effects
				(font
					(size 1 1)
					(thickness 0.15)
				)
				(justify mirror)
			)
		)
		(sheetname "Peripherals")
		(sheetfile "peripherals.kicad_sch")
		(attr smd)
		(fp_rect
			(start -0.925 0.47)
			(end 0.925 -0.47)
			(stroke
				(width 0.05)
				(type default)
			)
			(fill none)
			(layer "B.CrtYd")
		)
		(fp_line
			(start 0.504 -0.248)
			(end 0.504 0.25)
			(stroke
				(width 0.15)
				(type solid)
			)
			(layer "B.Fab")
		)
		(fp_line
			(start -0.494 -0.248)
			(end 0.504 -0.248)
			(stroke
				(width 0.15)
				(type solid)
			)
			(layer "B.Fab")
		)
		(fp_line
			(start 0.504 0.25)
			(end -0.494 0.25)
			(stroke
				(width 0.15)
				(type solid)
			)
			(layer "B.Fab")
		)
		(fp_line
			(start -0.494 0.25)
			(end -0.494 -0.248)
			(stroke
				(width 0.15)
				(type solid)
			)
			(layer "B.Fab")
		)
		(fp_text user "License: Apache-2.0"
			(at -0.932 -5.17 -90)
			(layer "B.Fab")
			(hide yes)
			(effects
				(font
					(size 0.7 0.7)
					(thickness 0.15)
				)
				(justify left bottom mirror)
			)
		)
		(fp_text user "${REFERENCE}"
			(at -0.932 -3.168 -90)
			(layer "B.Fab")
			(hide yes)
			(effects
				(font
					(size 0.7 0.7)
					(thickness 0.15)
				)
				(justify left bottom mirror)
			)
		)
		(fp_text user "Author: Antmicro"
			(at -0.932 -4.17 -90)
			(layer "B.Fab")
			(hide yes)
			(effects
				(font
					(size 0.7 0.7)
					(thickness 0.15)
				)
				(justify left bottom mirror)
			)
		)
		(pad "1" smd roundrect
			(at -0.48 0 90)
			(size 0.59 0.64)
			(layers "B.Cu" "B.Paste" "B.Mask")
			(roundrect_rratio 0.25)
			(net 1 "GND")
			(pintype "passive")
		)
		(pad "2" smd roundrect
			(at 0.48 0 90)
			(size 0.59 0.64)
			(layers "B.Cu" "B.Paste" "B.Mask")
			(roundrect_rratio 0.25)
			(net 87 "+3V3")
			(pintype "passive")
		)
	)
	(footprint "antmicro-footprints:R_Array_4x0201_Panasonic_EXB18V"
		(layer "B.Cu")
		(at 83.21 122.11 180)
		(property "Reference" "R204"
			(at 1.96 0.71 0)
			(layer "B.SilkS")
			(effects
				(font
					(size 0.7 0.7)
					(thickness 0.15)
				)
				(justify right bottom mirror)
			)
		)
		(property "Value" "R_4x0R_0201_array"
			(at -1.1 -1.8 0)
			(layer "B.Fab")
			(effects
				(font
					(size 0.7 0.7)
					(thickness 0.15)
				)
				(justify left bottom mirror)
			)
		)
		(property "Footprint" "antmicro-footprints:R_Array_4x0201_Panasonic_EXB18V"
			(at 0 0 180)
			(layer "F.Fab")
			(hide yes)
			(effects
				(font
					(size 1.27 1.27)
					(thickness 0.15)
				)
			)
		)
		(property "Datasheet" "http://industrial.panasonic.com/cdbs/www-data/pdf/AOC0000/AOC0000C14.pdf"
			(at 0 0 180)
			(layer "F.Fab")
			(hide yes)
			(effects
				(font
					(size 1.27 1.27)
					(thickness 0.15)
				)
			)
		)
		(property "Author" "Antmicro"
			(at 166.42 244.22 0)
			(layer "B.Fab")
			(hide yes)
			(effects
				(font
					(size 1 1)
					(thickness 0.15)
				)
				(justify mirror)
			)
		)
		(property "License" "Apache-2.0"
			(at 166.42 244.22 0)
			(layer "B.Fab")
			(hide yes)
			(effects
				(font
					(size 1 1)
					(thickness 0.15)
				)
				(justify mirror)
			)
		)
		(property "MPN" "EXB-18VR000X"
			(at 166.42 244.22 0)
			(layer "B.Fab")
			(hide yes)
			(effects
				(font
					(size 1 1)
					(thickness 0.15)
				)
				(justify mirror)
			)
		)
		(property "Manufacturer" "Panasonic"
			(at 166.42 244.22 0)
			(layer "B.Fab")
			(hide yes)
			(effects
				(font
					(size 1 1)
					(thickness 0.15)
				)
				(justify mirror)
			)
		)
		(property "Val" "4x0R_0201"
			(at 166.42 244.22 0)
			(layer "B.Fab")
			(hide yes)
			(effects
				(font
					(size 1 1)
					(thickness 0.15)
				)
				(justify mirror)
			)
		)
		(sheetname "Peripherals")
		(sheetfile "peripherals.kicad_sch")
		(attr smd)
		(fp_line
			(start 0.8 -0.45)
			(end 0.8 0.45)
			(stroke
				(width 0.12)
				(type solid)
			)
			(layer "B.SilkS")
		)
		(fp_line
			(start -0.8 -0.45)
			(end -0.8 0.45)
			(stroke
				(width 0.12)
				(type solid)
			)
			(layer "B.SilkS")
		)
		(fp_rect
			(start -0.898 0.66)
			(end 0.898 -0.65)
			(stroke
				(width 0.05)
				(type solid)
			)
			(fill none)
			(layer "B.CrtYd")
		)
		(fp_text user "${REFERENCE}"
			(at -1.051 -3.2 0)
			(layer "B.Fab")
			(hide yes)
			(effects
				(font
					(size 0.7 0.7)
					(thickness 0.15)
				)
				(justify left bottom mirror)
			)
		)
		(fp_text user "Author: Antmicro"
			(at -1.051 -4.599 0)
			(layer "B.Fab")
			(hide yes)
			(effects
				(font
					(size 0.7 0.7)
					(thickness 0.15)
				)
				(justify left bottom mirror)
			)
		)
		(fp_text user "License: Apache-2.0"
			(at -1.051 -6 0)
			(layer "B.Fab")
			(hide yes)
			(effects
				(font
					(size 0.7 0.7)
					(thickness 0.15)
				)
				(justify left bottom mirror)
			)
		)
		(pad "1" smd roundrect
			(at -0.6 -0.298 180)
			(size 0.2 0.4)
			(layers "B.Cu" "B.Paste" "B.Mask")
			(roundrect_rratio 0.25)
			(net 772 "/Peripherals/~{CS}")
			(pinfunction "R1.1")
			(pintype "passive")
		)
		(pad "2" smd roundrect
			(at -0.202 -0.298 180)
			(size 0.2 0.4)
			(layers "B.Cu" "B.Paste" "B.Mask")
			(roundrect_rratio 0.25)
			(net 774 "/Peripherals/MOSI")
			(pinfunction "R2.1")
			(pintype "passive")
		)
		(pad "3" smd roundrect
			(at 0.2 -0.298 180)
			(size 0.2 0.4)
			(layers "B.Cu" "B.Paste" "B.Mask")
			(roundrect_rratio 0.25)
			(net 671 "/Peripherals/SCK")
			(pinfunction "R3.1")
			(pintype "passive")
		)
		(pad "4" smd roundrect
			(at 0.598 -0.298 180)
			(size 0.2 0.4)
			(layers "B.Cu" "B.Paste" "B.Mask")
			(roundrect_rratio 0.25)
			(net 773 "/Peripherals/MISO")
			(pinfunction "R4.1")
			(pintype "passive")
		)
		(pad "5" smd roundrect
			(at 0.598 0.3 180)
			(size 0.2 0.4)
			(layers "B.Cu" "B.Paste" "B.Mask")
			(roundrect_rratio 0.25)
			(net 255 "PDC_MISO")
			(pinfunction "R4.2")
			(pintype "passive")
		)
		(pad "6" smd roundrect
			(at 0.2 0.3 180)
			(size 0.2 0.4)
			(layers "B.Cu" "B.Paste" "B.Mask")
			(roundrect_rratio 0.25)
			(net 254 "PDC_SCLK")
			(pinfunction "R3.2")
			(pintype "passive")
		)
		(pad "7" smd roundrect
			(at -0.202 0.3 180)
			(size 0.2 0.4)
			(layers "B.Cu" "B.Paste" "B.Mask")
			(roundrect_rratio 0.25)
			(net 256 "PDC_MOSI")
			(pinfunction "R2.2")
			(pintype "passive")
		)
		(pad "8" smd roundrect
			(at -0.6 0.3 180)
			(size 0.2 0.4)
			(layers "B.Cu" "B.Paste" "B.Mask")
			(roundrect_rratio 0.25)
			(net 253 "~{PDC_CS}")
			(pinfunction "R1.2")
			(pintype "passive")
		)
	)
	(footprint "antmicro-footprints:Spacer_Drill3.7mm_H6.5mm_9774065151R"
		(locked yes)
		(layer "B.Cu")
		(at 37.25 76.25 180)
		(descr "Spacer M=3 h=6.5mm fi=5.1mm")
		(property "Reference" "H6"
			(at -3.65 -3.15 0)
			(layer "B.SilkS")
			(effects
				(font
					(size 0.7 0.7)
					(thickness 0.15)
				)
				(justify left bottom mirror)
			)
		)
		(property "Value" "Spacer_Drill3.7mm_H6.5mm_9774065151R"
			(at 0 -4 0)
			(layer "B.Fab")
			(effects
				(font
					(size 0.7 0.7)
					(thickness 0.15)
				)
				(justify left bottom mirror)
			)
		)
		(property "Footprint" "antmicro-footprints:Spacer_Drill3.7mm_H6.5mm_9774065151R"
			(at 0 0 180)
			(layer "F.Fab")
			(hide yes)
			(effects
				(font
					(size 1.27 1.27)
					(thickness 0.15)
				)
			)
		)
		(property "Datasheet" "https://www.we-online.com/components/products/datasheet/9774065151R.pdf"
			(at 0 0 180)
			(layer "F.Fab")
			(hide yes)
			(effects
				(font
					(size 1.27 1.27)
					(thickness 0.15)
				)
			)
		)
		(property "Author" "Antmicro"
			(at 74.5 152.5 0)
			(layer "B.Fab")
			(hide yes)
			(effects
				(font
					(size 1 1)
					(thickness 0.15)
				)
				(justify mirror)
			)
		)
		(property "License" "Apache-2.0"
			(at 74.5 152.5 0)
			(layer "B.Fab")
			(hide yes)
			(effects
				(font
					(size 1 1)
					(thickness 0.15)
				)
				(justify mirror)
			)
		)
		(property "MPN" "9774065151R"
			(at 74.5 152.5 0)
			(layer "B.Fab")
			(hide yes)
			(effects
				(font
					(size 1 1)
					(thickness 0.15)
				)
				(justify mirror)
			)
		)
		(property "Manufacturer" "Würth Elektronik"
			(at 74.5 152.5 0)
			(layer "B.Fab")
			(hide yes)
			(effects
				(font
					(size 1 1)
					(thickness 0.15)
				)
				(justify mirror)
			)
		)
		(sheetname "Root")
		(sheetfile "jetson-orin-baseboard.kicad_sch")
		(solder_paste_ratio -1)
		(attr smd)
		(fp_circle
			(center 0 0)
			(end 3.05 0)
			(stroke
				(width 0.05)
				(type solid)
			)
			(fill none)
			(layer "B.CrtYd")
		)
		(fp_circle
			(center 0 0)
			(end 2.6 0)
			(stroke
				(width 0.15)
				(type solid)
			)
			(fill none)
			(layer "B.Fab")
		)
		(fp_text user "Author: Antmicro"
			(at -9.6 -7.7 0)
			(layer "B.Fab")
			(hide yes)
			(effects
				(font
					(size 0.7 0.7)
					(thickness 0.15)
				)
				(justify left bottom mirror)
			)
		)
		(fp_text user "License: Apache-2.0"
			(at -9.6 -8.9 0)
			(layer "B.Fab")
			(hide yes)
			(effects
				(font
					(size 0.7 0.7)
					(thickness 0.15)
				)
				(justify left bottom mirror)
			)
		)
		(fp_text user "${REFERENCE}"
			(at -9.6 -6.5 0)
			(layer "B.Fab")
			(hide yes)
			(effects
				(font
					(size 0.7 0.7)
					(thickness 0.15)
				)
				(justify left bottom mirror)
			)
		)
		(pad "" smd custom
			(at -1.7 -1.7 90)
			(size 0.62 0.62)
			(layers "B.Paste")
			(thermal_bridge_angle 90)
			(options
				(clearance outline)
				(anchor circle)
			)
			(primitives
				(gr_arc
					(start 1.266786 0.24747)
					(mid 0.285453 -0.29439)
					(end -0.250195 -1.279127)
					(width 0.2)
				)
				(gr_arc
					(start 1.259603 0.339191)
					(mid 0.218448 -0.232561)
					(end -0.34334 -1.279127)
					(width 0.2)
				)
				(gr_arc
					(start 1.255279 0.431435)
					(mid 0.152481 -0.169693)
					(end -0.436309 -1.279127)
					(width 0.2)
				)
				(gr_arc
					(start 1.253811 0.524161)
					(mid 0.087542 -0.105784)
					(end -0.529126 -1.279127)
					(width 0.2)
				)
				(gr_arc
					(start 1.275473 0.621136)
					(mid 0.0309 -0.033527)
					(end -0.621807 -1.279127)
					(width 0.2)
				)
				(gr_arc
					(start 1.263664 0.711602)
					(mid -0.037759 0.026651)
					(end -0.71437 -1.279127)
					(width 0.2)
				)
				(gr_arc
					(start 1.253435 0.802342)
					(mid -0.105837 0.087395)
					(end -0.806826 -1.279127)
					(width 0.2)
				)
				(gr_arc
					(start 1.267475 0.897258)
					(mid -0.165236 0.156885)
					(end -0.899187 -1.279127)
					(width 0.2)
				)
				(gr_arc
					(start 1.270645 0.990112)
					(mid -0.228522 0.222449)
					(end -0.991463 -1.279127)
					(width 0.2)
				)
				(gr_arc
					(start 1.266278 1.081674)
					(mid -0.294507 0.285313)
					(end -1.083663 -1.279127)
					(width 0.2)
				)
				(gr_line
					(start 1.279127 0.250195)
					(end 1.279127 1.083663)
					(width 0.2)
				)
				(gr_line
					(start -0.250195 -1.279127)
					(end -1.083663 -1.279127)
					(width 0.2)
				)
			)
		)
		(pad "" smd custom
			(at -1.7 1.7 180)
			(size 0.62 0.62)
			(layers "B.Paste")
			(thermal_bridge_angle 90)
			(options
				(clearance outline)
				(anchor circle)
			)
			(primitives
				(gr_arc
					(start 1.266786 0.24747)
					(mid 0.285453 -0.29439)
					(end -0.250195 -1.279127)
					(width 0.2)
				)
				(gr_arc
					(start 1.259603 0.339191)
					(mid 0.218448 -0.232561)
					(end -0.34334 -1.279127)
					(width 0.2)
				)
				(gr_arc
					(start 1.255279 0.431435)
					(mid 0.152481 -0.169693)
					(end -0.436309 -1.279127)
					(width 0.2)
				)
				(gr_arc
					(start 1.253811 0.524161)
					(mid 0.087542 -0.105784)
					(end -0.529126 -1.279127)
					(width 0.2)
				)
				(gr_arc
					(start 1.275473 0.621136)
					(mid 0.0309 -0.033527)
					(end -0.621807 -1.279127)
					(width 0.2)
				)
				(gr_arc
					(start 1.263664 0.711602)
					(mid -0.037759 0.026651)
					(end -0.71437 -1.279127)
					(width 0.2)
				)
				(gr_arc
					(start 1.253435 0.802342)
					(mid -0.105837 0.087395)
					(end -0.806826 -1.279127)
					(width 0.2)
				)
				(gr_arc
					(start 1.267475 0.897258)
					(mid -0.165236 0.156885)
					(end -0.899187 -1.279127)
					(width 0.2)
				)
				(gr_arc
					(start 1.270645 0.990112)
					(mid -0.228522 0.222449)
					(end -0.991463 -1.279127)
					(width 0.2)
				)
				(gr_arc
					(start 1.266278 1.081674)
					(mid -0.294507 0.285313)
					(end -1.083663 -1.279127)
					(width 0.2)
				)
				(gr_line
					(start 1.279127 0.250195)
					(end 1.279127 1.083663)
					(width 0.2)
				)
				(gr_line
					(start -0.250195 -1.279127)
					(end -1.083663 -1.279127)
					(width 0.2)
				)
			)
		)
		(pad "" smd custom
			(at 1.7 -1.7)
			(size 0.62 0.62)
			(layers "B.Paste")
			(thermal_bridge_angle 90)
			(options
				(clearance outline)
				(anchor circle)
			)
			(primitives
				(gr_arc
					(start 1.266786 0.24747)
					(mid 0.285453 -0.29439)
					(end -0.250195 -1.279127)
					(width 0.2)
				)
				(gr_arc
					(start 1.259603 0.339191)
					(mid 0.218448 -0.232561)
					(end -0.34334 -1.279127)
					(width 0.2)
				)
				(gr_arc
					(start 1.255279 0.431435)
					(mid 0.152481 -0.169693)
					(end -0.436309 -1.279127)
					(width 0.2)
				)
				(gr_arc
					(start 1.253811 0.524161)
					(mid 0.087542 -0.105784)
					(end -0.529126 -1.279127)
					(width 0.2)
				)
				(gr_arc
					(start 1.275473 0.621136)
					(mid 0.0309 -0.033527)
					(end -0.621807 -1.279127)
					(width 0.2)
				)
				(gr_arc
					(start 1.263664 0.711602)
					(mid -0.037759 0.026651)
					(end -0.71437 -1.279127)
					(width 0.2)
				)
				(gr_arc
					(start 1.253435 0.802342)
					(mid -0.105837 0.087395)
					(end -0.806826 -1.279127)
					(width 0.2)
				)
				(gr_arc
					(start 1.267475 0.897258)
					(mid -0.165236 0.156885)
					(end -0.899187 -1.279127)
					(width 0.2)
				)
				(gr_arc
					(start 1.270645 0.990112)
					(mid -0.228522 0.222449)
					(end -0.991463 -1.279127)
					(width 0.2)
				)
				(gr_arc
					(start 1.266278 1.081674)
					(mid -0.294507 0.285313)
					(end -1.083663 -1.279127)
					(width 0.2)
				)
				(gr_line
					(start 1.279127 0.250195)
					(end 1.279127 1.083663)
					(width 0.2)
				)
				(gr_line
					(start -0.250195 -1.279127)
					(end -1.083663 -1.279127)
					(width 0.2)
				)
			)
		)
		(pad "" smd custom
			(at 1.7 1.7 270)
			(size 0.62 0.62)
			(layers "B.Paste")
			(thermal_bridge_angle 90)
			(options
				(clearance outline)
				(anchor circle)
			)
			(primitives
				(gr_arc
					(start 1.266786 0.24747)
					(mid 0.285453 -0.29439)
					(end -0.250195 -1.279127)
					(width 0.2)
				)
				(gr_arc
					(start 1.259603 0.339191)
					(mid 0.218448 -0.232561)
					(end -0.34334 -1.279127)
					(width 0.2)
				)
				(gr_arc
					(start 1.255279 0.431435)
					(mid 0.152481 -0.169693)
					(end -0.436309 -1.279127)
					(width 0.2)
				)
				(gr_arc
					(start 1.253811 0.524161)
					(mid 0.087542 -0.105784)
					(end -0.529126 -1.279127)
					(width 0.2)
				)
				(gr_arc
					(start 1.275473 0.621136)
					(mid 0.0309 -0.033527)
					(end -0.621807 -1.279127)
					(width 0.2)
				)
				(gr_arc
					(start 1.263664 0.711602)
					(mid -0.037759 0.026651)
					(end -0.71437 -1.279127)
					(width 0.2)
				)
				(gr_arc
					(start 1.253435 0.802342)
					(mid -0.105837 0.087395)
					(end -0.806826 -1.279127)
					(width 0.2)
				)
				(gr_arc
					(start 1.267475 0.897258)
					(mid -0.165236 0.156885)
					(end -0.899187 -1.279127)
					(width 0.2)
				)
				(gr_arc
					(start 1.270645 0.990112)
					(mid -0.228522 0.222449)
					(end -0.991463 -1.279127)
					(width 0.2)
				)
				(gr_arc
					(start 1.266278 1.081674)
					(mid -0.294507 0.285313)
					(end -1.083663 -1.279127)
					(width 0.2)
				)
				(gr_line
					(start 1.279127 0.250195)
					(end 1.279127 1.083663)
					(width 0.2)
				)
				(gr_line
					(start -0.250195 -1.279127)
					(end -1.083663 -1.279127)
					(width 0.2)
				)
			)
		)
		(pad "1" thru_hole circle
			(at 0 0 180)
			(size 6 6)
			(drill 3.7)
			(layers "*.Cu" "*.Mask")
			(remove_unused_layers no)
			(net 1 "GND")
			(pintype "passive")
		)
	)
)
